# S9S_MB_2U (Grand Teton) — schematic netlist excerpt (pin names and nets, part order shuffled) for the footprints in the layout excerpt that follows; sources: Cadence DE-HDL packaged netlist, KiCad conversion of 03242023_DA0F0TMBIJ0_F0T_Motherboard_J_brd_V01_OCP.brd

PR4230  Q_RES  0 5% CHIP  pkg 0402LF  page 278 : A = NC_PVCCD_HV_CPU0_ACSP2 ; B = GND

U83  GTL2014PW  IC  pkg TSSOP14  page 239
  DIR  = PD_GTL2014_BMC_JTAG_DIR_2
  B0  = PD_JTAG_DBP_B0
  B1  = JTAG_DBP_PRDY_R_N
  VREF  = P0V7_JTAG_VREF_2
  B2  = PD_JTAG_DBP_B2
  B3  = JTAG_DBP_FB_TDO
  GND_0  = GND
  GND_1  = GND
  A3  = JTAG_BMC_DBP_TDO_R
  A2  = TP_JTAG_BMC_A2
  GND_2  = GND
  A1  = JTAG_DBP_BMC_PRDY_R1_N
  A0  = TP_JTAG_BMC_A0
  VCC  = P3V3_AUX

(kicad_pcb
	(version 20260206)
	(generator "pcbnew")
	(generator_version "10.0")
	(general
		(thickness 1.6)
		(legacy_teardrops no)
	)
	(paper "A4")
	(title_block
		(title "03242023_DA0F0TMBIJ0_F0T_Motherboard_J_brd_V01_OCP.brd")
		(comment 1 "Grand Teton / footprints 2266-2267 of 6105")
	)
	(layers
		(0 "F.Cu" signal "TOP")
		(4 "In1.Cu" signal "GND")
		(6 "In2.Cu" signal "IN1")
		(8 "In3.Cu" signal "GND1")
		(10 "In4.Cu" signal "IN2")
		(12 "In5.Cu" signal "GND2")
		(14 "In6.Cu" signal "IN3")
		(16 "In7.Cu" signal "GND3")
		(18 "In8.Cu" signal "VCC")
		(20 "In9.Cu" signal "VCC1")
		(22 "In10.Cu" signal "GND4")
		(24 "In11.Cu" signal "IN4")
		(26 "In12.Cu" signal "GND5")
		(28 "In13.Cu" signal "IN5")
		(30 "In14.Cu" signal "GND6")
		(32 "In15.Cu" signal "IN6")
		(34 "In16.Cu" signal "GND7")
		(2 "B.Cu" signal "BOTTOM")
		(9 "F.Adhes" user "F.Adhesive")
		(11 "B.Adhes" user "B.Adhesive")
		(13 "F.Paste" user "Package Geometry/Pastemask Top")
		(15 "B.Paste" user "Package Geometry/Pastemask Bottom")
		(5 "F.SilkS" user "Ref Des/Silkscreen Top")
		(7 "B.SilkS" user "Ref Des/Silkscreen Bottom")
		(1 "F.Mask" user "Board Geometry/Soldermask Top")
		(3 "B.Mask" user "Board Geometry/Soldermask Bottom")
		(17 "Dwgs.User" user "User.Drawings")
		(19 "Cmts.User" user "User.Comments")
		(21 "Eco1.User" user "User.Eco1")
		(23 "Eco2.User" user "User.Eco2")
		(25 "Edge.Cuts" user "Board Geometry/Outline")
		(27 "Margin" user)
		(31 "F.CrtYd" user "Package Geometry/Place Bound Top")
		(29 "B.CrtYd" user "Package Geometry/Place Bound Bottom")
		(35 "F.Fab" user "Ref Des/Assembly Top")
		(33 "B.Fab" user "Ref Des/Assembly Bottom")
	)
	(footprint ""
		(layer "F.Cu")
		(at 377.668536 -99.133152 -90)
		(property "Reference" "U83"
			(at -1.032002 -3.3909 0)
			(unlocked yes)
			(layer "F.SilkS")
			(effects
				(font
					(size 0.7874 0.5842)
					(thickness 0.1524)
				)
				(justify left)
			)
		)
		(property "Value" ""
			(at 0 0 270)
			(layer "F.Fab")
			(effects
				(font
					(size 1.27 1.27)
				)
			)
		)
		(duplicate_pad_numbers_are_jumpers no)
		(fp_line
			(start -2.0066 2.5527)
			(end -2.0066 -2.5527)
			(stroke
				(width 0.1524)
				(type default)
			)
			(layer "F.SilkS")
		)
		(fp_line
			(start 2.0066 2.5527)
			(end -2.0066 2.5527)
			(stroke
				(width 0.1524)
				(type default)
			)
			(layer "F.SilkS")
		)
		(fp_line
			(start 0 -1.9812)
			(end 0.5715 -2.5527)
			(stroke
				(width 0.1524)
				(type default)
			)
			(layer "F.SilkS")
		)
		(fp_line
			(start -2.0066 -2.5527)
			(end -0.5715 -2.5527)
			(stroke
				(width 0.1524)
				(type default)
			)
			(layer "F.SilkS")
		)
		(fp_line
			(start -0.5715 -2.5527)
			(end 0 -1.9812)
			(stroke
				(width 0.1524)
				(type default)
			)
			(layer "F.SilkS")
		)
		(fp_line
			(start 0.5715 -2.5527)
			(end 2.0066 -2.5527)
			(stroke
				(width 0.1524)
				(type default)
			)
			(layer "F.SilkS")
		)
		(fp_line
			(start 2.0066 -2.5527)
			(end 2.0066 2.5527)
			(stroke
				(width 0.1524)
				(type default)
			)
			(layer "F.SilkS")
		)
		(fp_poly
			(pts
				(xy -2.712212 -2.987548) (xy -3.04038 -2.433828) (xy -3.337052 -2.987548)
			)
			(stroke
				(width 0)
				(type default)
			)
			(fill yes)
			(layer "F.SilkS")
		)
		(fp_line
			(start -2.249932 2.549906)
			(end -2.249932 -2.549906)
			(stroke
				(width 0.1)
				(type default)
			)
			(layer "F.Fab")
		)
		(fp_line
			(start 2.249932 2.549906)
			(end -2.249932 2.549906)
			(stroke
				(width 0.1)
				(type default)
			)
			(layer "F.Fab")
		)
		(fp_line
			(start -2.249932 -2.549906)
			(end 2.249932 -2.549906)
			(stroke
				(width 0.1)
				(type default)
			)
			(layer "F.Fab")
		)
		(fp_line
			(start 2.249932 -2.549906)
			(end 2.249932 2.549906)
			(stroke
				(width 0.1)
				(type default)
			)
			(layer "F.Fab")
		)
		(fp_poly
			(pts
				(xy -4.36372 -1.608328) (xy -4.36372 -2.233168) (xy -3.81 -1.905)
			)
			(stroke
				(width 0)
				(type default)
			)
			(fill yes)
			(layer "F.Fab")
		)
		(pad "1" smd rect
			(at -2.921 -1.949958 180)
			(size 0.3556 1.4986)
			(layers "F.Cu" "F.Mask" "F.Paste")
			(net "PD_GTL2014_BMC_JTAG_DIR_2")
		)
		(pad "2" smd rect
			(at -2.921 -1.299972 180)
			(size 0.3556 1.4986)
			(layers "F.Cu" "F.Mask" "F.Paste")
			(net "PD_JTAG_DBP_B0")
		)
		(pad "3" smd rect
			(at -2.921 -0.649986 180)
			(size 0.3556 1.4986)
			(layers "F.Cu" "F.Mask" "F.Paste")
			(net "JTAG_DBP_PRDY_R_N")
		)
		(pad "4" smd rect
			(at -2.921 0 180)
			(size 0.3556 1.4986)
			(layers "F.Cu" "F.Mask" "F.Paste")
			(net "P0V7_JTAG_VREF_2")
		)
		(pad "5" smd rect
			(at -2.921 0.649986 180)
			(size 0.3556 1.4986)
			(layers "F.Cu" "F.Mask" "F.Paste")
			(net "PD_JTAG_DBP_B2")
		)
		(pad "6" smd rect
			(at -2.921 1.299972 180)
			(size 0.3556 1.4986)
			(layers "F.Cu" "F.Mask" "F.Paste")
			(net "JTAG_DBP_FB_TDO")
		)
		(pad "7" smd rect
			(at -2.921 1.949958 180)
			(size 0.3556 1.4986)
			(layers "F.Cu" "F.Mask" "F.Paste")
			(net "GND")
		)
		(pad "8" smd rect
			(at 2.921 1.949958 180)
			(size 0.3556 1.4986)
			(layers "F.Cu" "F.Mask" "F.Paste")
			(net "GND")
		)
		(pad "9" smd rect
			(at 2.921 1.299972 180)
			(size 0.3556 1.4986)
			(layers "F.Cu" "F.Mask" "F.Paste")
			(net "JTAG_BMC_DBP_TDO_R")
		)
		(pad "10" smd rect
			(at 2.921 0.649986 180)
			(size 0.3556 1.4986)
			(layers "F.Cu" "F.Mask" "F.Paste")
			(net "TP_JTAG_BMC_A2")
		)
		(pad "11" smd rect
			(at 2.921 0 180)
			(size 0.3556 1.4986)
			(layers "F.Cu" "F.Mask" "F.Paste")
			(net "GND")
		)
		(pad "12" smd rect
			(at 2.921 -0.649986 180)
			(size 0.3556 1.4986)
			(layers "F.Cu" "F.Mask" "F.Paste")
			(net "JTAG_DBP_BMC_PRDY_R1_N")
		)
		(pad "13" smd rect
			(at 2.921 -1.299972 180)
			(size 0.3556 1.4986)
			(layers "F.Cu" "F.Mask" "F.Paste")
			(net "TP_JTAG_BMC_A0")
		)
		(pad "14" smd rect
			(at 2.921 -1.949958 180)
			(size 0.3556 1.4986)
			(layers "F.Cu" "F.Mask" "F.Paste")
			(net "P3V3_AUX")
		)
	)
	(footprint ""
		(layer "F.Cu")
		(at 432.74488 -128.361948 90)
		(property "Reference" "PR4230"
			(at 0 0 90)
			(layer "F.SilkS")
			(hide yes)
			(effects
				(font
					(size 1.27 1.27)
				)
			)
		)
		(property "Value" ""
			(at 0 0 90)
			(layer "F.Fab")
			(effects
				(font
					(size 1.27 1.27)
				)
			)
		)
		(duplicate_pad_numbers_are_jumpers no)
		(fp_line
			(start 0.7874 -0.4064)
			(end 0.7874 0.4064)
			(stroke
				(width 0.1524)
				(type default)
			)
			(layer "F.SilkS")
		)
		(fp_line
			(start -0.7874 -0.4064)
			(end 0.7874 -0.4064)
			(stroke
				(width 0.1524)
				(type default)
			)
			(layer "F.SilkS")
		)
		(fp_line
			(start 0.7874 0.4064)
			(end -0.7874 0.4064)
			(stroke
				(width 0.1524)
				(type default)
			)
			(layer "F.SilkS")
		)
		(fp_line
			(start -0.7874 0.4064)
			(end -0.7874 -0.4064)
			(stroke
				(width 0.1524)
				(type default)
			)
			(layer "F.SilkS")
		)
		(fp_line
			(start -0.12065 -0.305054)
			(end -0.12065 -0.2794)
			(stroke
				(width 0.1)
				(type default)
			)
			(layer "F.Fab")
		)
		(fp_line
			(start -0.67945 -0.305054)
			(end -0.12065 -0.305054)
			(stroke
				(width 0.1)
				(type default)
			)
			(layer "F.Fab")
		)
		(fp_line
			(start 0.67945 -0.3048)
			(end 0.67945 0.3048)
			(stroke
				(width 0.1)
				(type default)
			)
			(layer "F.Fab")
		)
		(fp_line
			(start 0.12065 -0.3048)
			(end 0.67945 -0.3048)
			(stroke
				(width 0.1)
				(type default)
			)
			(layer "F.Fab")
		)
		(fp_line
			(start 0.12065 -0.2794)
			(end 0.12065 -0.3048)
			(stroke
				(width 0.1)
				(type default)
			)
			(layer "F.Fab")
		)
		(fp_line
			(start -0.12065 -0.2794)
			(end 0.12065 -0.2794)
			(stroke
				(width 0.1)
				(type default)
			)
			(layer "F.Fab")
		)
		(fp_line
			(start 0.120396 0.2794)
			(end -0.12065 0.2794)
			(stroke
				(width 0.1)
				(type default)
			)
			(layer "F.Fab")
		)
		(fp_line
			(start -0.12065 0.2794)
			(end -0.12065 0.3048)
			(stroke
				(width 0.1)
				(type default)
			)
			(layer "F.Fab")
		)
		(fp_line
			(start 0.67945 0.3048)
			(end 0.120396 0.3048)
			(stroke
				(width 0.1)
				(type default)
			)
			(layer "F.Fab")
		)
		(fp_line
			(start 0.120396 0.3048)
			(end 0.120396 0.2794)
			(stroke
				(width 0.1)
				(type default)
			)
			(layer "F.Fab")
		)
		(fp_line
			(start -0.12065 0.3048)
			(end -0.67945 0.3048)
			(stroke
				(width 0.1)
				(type default)
			)
			(layer "F.Fab")
		)
		(fp_line
			(start -0.67945 0.3048)
			(end -0.67945 -0.305054)
			(stroke
				(width 0.1)
				(type default)
			)
			(layer "F.Fab")
		)
		(pad "1" smd circle
			(at -0.40005 0 90)
			(size 0 0)
			(layers "F.Cu" "F.Mask" "F.Paste")
			(net "NC_PVCCD_HV_CPU0_ACSP2")
		)
		(pad "2" smd circle
			(at 0.40005 0 90)
			(size 0 0)
			(layers "F.Cu" "F.Mask" "F.Paste")
			(net "GND")
		)
	)
)
